# BASEBOARD_FAB2 (Tioga Pass) — schematic netlist excerpt (pin names and nets, part order shuffled) for the footprints in the layout excerpt that follows; sources: Cadence DE-HDL packaged netlist, KiCad conversion of Wiwynn_Tioga_Pass_MB.brd

SH4L1  SHUNT  EMPTY  pkg SH0201  page 220 : A = VSENSE_PVDDQ_DEF_N ; B = GND
R1U22  RES  2.7K 1% CHIP  pkg 0402  page 164 : A = P3V3_STBY ; B = FM_BOARD_SKU_ID1
C1M13  CAP  0.22UF 16V 10% X7R  pkg 0402  page 106 : A = P3E_CPU0_PE3_OCP_TXN<12> ; B = P3E_OCP_CPU0_PE3_C_TXN<12>

(kicad_pcb
	(version 20260206)
	(generator "pcbnew")
	(generator_version "10.0")
	(general
		(thickness 1.6)
		(legacy_teardrops no)
	)
	(paper "A4")
	(title_block
		(title "Wiwynn_Tioga_Pass_MB.brd")
		(comment 1 "Tioga Pass / footprints 4547-4549 of 4770")
	)
	(layers
		(0 "F.Cu" signal "TOP")
		(4 "In1.Cu" signal "L2GND")
		(6 "In2.Cu" signal "L3")
		(8 "In3.Cu" signal "L4GND")
		(10 "In4.Cu" signal "L5")
		(12 "In5.Cu" signal "L6GND")
		(14 "In6.Cu" signal "L7VCC")
		(16 "In7.Cu" signal "L8VCC")
		(18 "In8.Cu" signal "L9GND")
		(20 "In9.Cu" signal "L10")
		(22 "In10.Cu" signal "L11GND")
		(24 "In11.Cu" signal "L12")
		(26 "In12.Cu" signal "L13GND")
		(2 "B.Cu" signal "BOTTOM")
		(9 "F.Adhes" user "F.Adhesive")
		(11 "B.Adhes" user "B.Adhesive")
		(13 "F.Paste" user "Package Geometry/Pastemask Top")
		(15 "B.Paste" user "Package Geometry/Pastemask Bottom")
		(5 "F.SilkS" user "Ref Des/Silkscreen Top")
		(7 "B.SilkS" user "Ref Des/Silkscreen Bottom")
		(1 "F.Mask" user "Board Geometry/Soldermask Top")
		(3 "B.Mask" user "Board Geometry/Soldermask Bottom")
		(17 "Dwgs.User" user "User.Drawings")
		(19 "Cmts.User" user "User.Comments")
		(21 "Eco1.User" user "User.Eco1")
		(23 "Eco2.User" user "User.Eco2")
		(25 "Edge.Cuts" user "Board Geometry/Outline")
		(27 "Margin" user)
		(31 "F.CrtYd" user "Package Geometry/Place Bound Top")
		(29 "B.CrtYd" user "Package Geometry/Place Bound Bottom")
		(35 "F.Fab" user "Ref Des/Assembly Top")
		(33 "B.Fab" user "Ref Des/Assembly Bottom")
	)
	(footprint ""
		(layer "B.Cu")
		(at 264.1346 -124.6886 -90)
		(property "Reference" "SH4L1"
			(at 0 0 90)
			(layer "B.SilkS")
			(hide yes)
			(effects
				(font
					(size 1.27 1.27)
				)
				(justify mirror)
			)
		)
		(property "Value" ""
			(at 0 0 90)
			(layer "B.Fab")
			(effects
				(font
					(size 1.27 1.27)
				)
				(justify mirror)
			)
		)
		(duplicate_pad_numbers_are_jumpers no)
		(fp_poly
			(pts
				(xy 0.1651 -0.0508) (xy 0.1651 0.5842) (xy -0.1651 0.5842) (xy -0.1651 -0.0508)
			)
			(stroke
				(width 0)
				(type default)
			)
			(fill no)
			(layer "B.CrtYd")
		)
		(fp_line
			(start -0.1651 0.5842)
			(end 0.1651 0.5842)
			(stroke
				(width 0.1)
				(type default)
			)
			(layer "B.Fab")
		)
		(fp_line
			(start 0.1651 0.5842)
			(end 0.1651 -0.0508)
			(stroke
				(width 0.1)
				(type default)
			)
			(layer "B.Fab")
		)
		(fp_line
			(start -0.1651 -0.0508)
			(end -0.1651 0.5842)
			(stroke
				(width 0.1)
				(type default)
			)
			(layer "B.Fab")
		)
		(fp_line
			(start 0.1651 -0.0508)
			(end -0.1651 -0.0508)
			(stroke
				(width 0.1)
				(type default)
			)
			(layer "B.Fab")
		)
		(pad "1" smd custom
			(at 0 0 270)
			(size 0.0762 0.0762)
			(layers "B.Cu" "B.Mask" "B.Paste")
			(net "VSENSE_PVDDQ_DEF_N")
			(options
				(clearance outline)
				(anchor circle)
			)
			(primitives
				(gr_poly
					(pts
						(arc
							(start -0.1524 0.10795)
							(mid -0.098518 0.130268)
							(end -0.0762 0.18415)
						)
						(xy -0.0762 0.22225) (xy 0.0762 0.22225)
						(arc
							(start 0.0762 0.18415)
							(mid 0.098518 0.130268)
							(end 0.1524 0.10795)
						)
						(xy 0.1524 -0.22225) (xy -0.1524 -0.22225)
					)
					(width 0)
					(fill yes)
				)
			)
		)
		(pad "2" smd custom
			(at 0 0.5334 90)
			(size 0.0762 0.0762)
			(layers "B.Cu" "B.Mask" "B.Paste")
			(net "GND")
			(options
				(clearance outline)
				(anchor circle)
			)
			(primitives
				(gr_poly
					(pts
						(arc
							(start -0.1524 0.10795)
							(mid -0.098518 0.130268)
							(end -0.0762 0.18415)
						)
						(xy -0.0762 0.22225) (xy 0.0762 0.22225)
						(arc
							(start 0.0762 0.18415)
							(mid 0.098518 0.130268)
							(end 0.1524 0.10795)
						)
						(xy 0.1524 -0.22225) (xy -0.1524 -0.22225)
					)
					(width 0)
					(fill yes)
				)
			)
		)
	)
	(footprint ""
		(layer "B.Cu")
		(at 455.676 -116.49202)
		(property "Reference" "C1M13"
			(at 0 0 0)
			(layer "B.SilkS")
			(hide yes)
			(effects
				(font
					(size 1.27 1.27)
				)
				(justify mirror)
			)
		)
		(property "Value" ""
			(at 0 0 0)
			(layer "B.Fab")
			(effects
				(font
					(size 1.27 1.27)
				)
				(justify mirror)
			)
		)
		(duplicate_pad_numbers_are_jumpers no)
		(fp_rect
			(start -0.3048 0.9906)
			(end 0.3048 -0.1016)
			(stroke
				(width 0)
				(type default)
			)
			(fill no)
			(layer "B.CrtYd")
		)
		(fp_line
			(start -0.3048 -0.1016)
			(end 0.3048 -0.1016)
			(stroke
				(width 0.1)
				(type default)
			)
			(layer "B.Fab")
		)
		(fp_line
			(start -0.3048 0.9906)
			(end -0.3048 -0.1016)
			(stroke
				(width 0.1)
				(type default)
			)
			(layer "B.Fab")
		)
		(fp_line
			(start 0.3048 -0.1016)
			(end 0.3048 0.9906)
			(stroke
				(width 0.1)
				(type default)
			)
			(layer "B.Fab")
		)
		(fp_line
			(start 0.3048 0.9906)
			(end -0.3048 0.9906)
			(stroke
				(width 0.1)
				(type default)
			)
			(layer "B.Fab")
		)
		(pad "1" smd rect
			(at 0 0 180)
			(size 0.508 0.508)
			(layers "B.Cu" "B.Mask" "B.Paste")
			(net "P3E_CPU0_PE3_OCP_TXN<12>")
		)
		(pad "2" smd rect
			(at 0 0.889 180)
			(size 0.508 0.508)
			(layers "B.Cu" "B.Mask" "B.Paste")
			(net "P3E_OCP_CPU0_PE3_C_TXN<12>")
		)
		(zone
			(layer "B.Cu")
			(hatch none 0.5)
			(connect_pads
				(clearance 0)
			)
			(min_thickness 0.25)
			(keepout
				(tracks allowed)
				(vias not_allowed)
				(pads allowed)
				(copperpour not_allowed)
				(footprints allowed)
			)
			(placement
				(enabled no)
				(sheetname "")
			)
			(fill
				(thermal_gap 0.5)
				(thermal_bridge_width 0.5)
				(island_removal_mode 0)
			)
			(polygon
				(pts
					(xy 455.422 -115.85702) (xy 455.93 -115.85702) (xy 455.93 -116.23802) (xy 455.422 -116.23802)
				)
			)
		)
		(zone
			(layer "B.Cu")
			(hatch none 0.5)
			(connect_pads
				(clearance 0)
			)
			(min_thickness 0.25)
			(keepout
				(tracks not_allowed)
				(vias allowed)
				(pads allowed)
				(copperpour not_allowed)
				(footprints allowed)
			)
			(placement
				(enabled no)
				(sheetname "")
			)
			(fill
				(thermal_gap 0.5)
				(thermal_bridge_width 0.5)
				(island_removal_mode 0)
			)
			(polygon
				(pts
					(xy 455.422 -115.85702) (xy 455.93 -115.85702) (xy 455.93 -116.23802) (xy 455.422 -116.23802)
				)
			)
		)
	)
	(footprint ""
		(layer "B.Cu")
		(at 427.9519 -18.034 90)
		(property "Reference" "R1U22"
			(at 0 0 90)
			(layer "B.SilkS")
			(hide yes)
			(effects
				(font
					(size 1.27 1.27)
				)
				(justify mirror)
			)
		)
		(property "Value" ""
			(at 0 0 90)
			(layer "B.Fab")
			(effects
				(font
					(size 1.27 1.27)
				)
				(justify mirror)
			)
		)
		(duplicate_pad_numbers_are_jumpers no)
		(fp_poly
			(pts
				(xy 0.2794 -0.1016) (xy -0.2794 -0.1016) (xy -0.2794 0.9906) (xy 0.2794 0.9906)
			)
			(stroke
				(width 0)
				(type default)
			)
			(fill no)
			(layer "B.CrtYd")
		)
		(fp_line
			(start 0.2794 -0.1016)
			(end 0.2794 0.9906)
			(stroke
				(width 0.1)
				(type default)
			)
			(layer "B.Fab")
		)
		(fp_line
			(start -0.2794 -0.1016)
			(end 0.2794 -0.1016)
			(stroke
				(width 0.1)
				(type default)
			)
			(layer "B.Fab")
		)
		(fp_line
			(start 0.2794 0.9906)
			(end -0.2794 0.9906)
			(stroke
				(width 0.1)
				(type default)
			)
			(layer "B.Fab")
		)
		(fp_line
			(start -0.2794 0.9906)
			(end -0.2794 -0.1016)
			(stroke
				(width 0.1)
				(type default)
			)
			(layer "B.Fab")
		)
		(pad "1" smd rect
			(at 0 0 270)
			(size 0.508 0.508)
			(layers "B.Cu" "B.Mask" "B.Paste")
			(net "P3V3_STBY")
		)
		(pad "2" smd rect
			(at 0 0.889 270)
			(size 0.508 0.508)
			(layers "B.Cu" "B.Mask" "B.Paste")
			(net "FM_BOARD_SKU_ID1")
		)
		(zone
			(layer "B.Cu")
			(hatch none 0.5)
			(connect_pads
				(clearance 0)
			)
			(min_thickness 0.25)
			(keepout
				(tracks allowed)
				(vias not_allowed)
				(pads allowed)
				(copperpour not_allowed)
				(footprints allowed)
			)
			(placement
				(enabled no)
				(sheetname "")
			)
			(fill
				(thermal_gap 0.5)
				(thermal_bridge_width 0.5)
				(island_removal_mode 0)
			)
			(polygon
				(pts
					(xy 428.2059 -18.288) (xy 428.2059 -17.78) (xy 428.5869 -17.78) (xy 428.5869 -18.288)
				)
			)
		)
		(zone
			(layer "B.Cu")
			(hatch none 0.5)
			(connect_pads
				(clearance 0)
			)
			(min_thickness 0.25)
			(keepout
				(tracks not_allowed)
				(vias allowed)
				(pads allowed)
				(copperpour not_allowed)
				(footprints allowed)
			)
			(placement
				(enabled no)
				(sheetname "")
			)
			(fill
				(thermal_gap 0.5)
				(thermal_bridge_width 0.5)
				(island_removal_mode 0)
			)
			(polygon
				(pts
					(xy 428.5869 -18.288) (xy 428.5869 -17.78) (xy 428.2059 -17.78) (xy 428.2059 -18.288)
				)
			)
		)
	)
)
